(kicad_pcb
	(version 20260206)
	(generator "pcbnew")
	(generator_version "10.0")
	(general
		(thickness 1.6)
		(legacy_teardrops no)
	)
	(paper "A4")
	(title_block
		(title "v1-chassis-manager — T6M_CM_d_v01_1031_1645.brd")
		(comment 1 "Open CloudServer (Microsoft) / footprints 1046-1049 of 2512")
	)
	(layers
		(0 "F.Cu" signal "TOP")
		(4 "In1.Cu" signal "GND1")
		(6 "In2.Cu" signal "IN1")
		(8 "In3.Cu" signal "VCC1")
		(10 "In4.Cu" signal "VCC2")
		(12 "In5.Cu" signal "GND2")
		(14 "In6.Cu" signal "IN2")
		(16 "In7.Cu" signal "IN3")
		(18 "In8.Cu" signal "GND3")
		(2 "B.Cu" signal "BOTTOM")
		(9 "F.Adhes" user "F.Adhesive")
		(11 "B.Adhes" user "B.Adhesive")
		(13 "F.Paste" user "Package Geometry/Pastemask Top")
		(15 "B.Paste" user "Package Geometry/Pastemask Bottom")
		(5 "F.SilkS" user "Ref Des/Silkscreen Top")
		(7 "B.SilkS" user "Ref Des/Silkscreen Bottom")
		(1 "F.Mask" user "Board Geometry/Soldermask Top")
		(3 "B.Mask" user "Board Geometry/Soldermask Bottom")
		(17 "Dwgs.User" user "User.Drawings")
		(19 "Cmts.User" user "User.Comments")
		(21 "Eco1.User" user "User.Eco1")
		(23 "Eco2.User" user "User.Eco2")
		(25 "Edge.Cuts" user "Board Geometry/Outline")
		(27 "Margin" user)
		(31 "F.CrtYd" user "Package Geometry/Place Bound Top")
		(29 "B.CrtYd" user "Package Geometry/Place Bound Bottom")
		(35 "F.Fab" user "Ref Des/Assembly Top")
		(33 "B.Fab" user "Ref Des/Assembly Bottom")
	)
	(footprint ""
		(layer "F.Cu")
		(at 108.67263 -164.1094)
		(property "Reference" "R759"
			(at 86.51875 69.344032 0)
			(unlocked yes)
			(layer "F.SilkS")
			(effects
				(font
					(size 0.7874 0.5842)
					(thickness 0.1524)
				)
				(justify left)
			)
		)
		(property "Value" ""
			(at 0 0 0)
			(layer "F.Fab")
			(effects
				(font
					(size 1.27 1.27)
				)
			)
		)
		(duplicate_pad_numbers_are_jumpers no)
		(fp_line
			(start -0.7874 -0.4064)
			(end 0.7874 -0.4064)
			(stroke
				(width 0.1524)
				(type default)
			)
			(layer "F.SilkS")
		)
		(fp_line
			(start -0.7874 0.4064)
			(end -0.7874 -0.4064)
			(stroke
				(width 0.1524)
				(type default)
			)
			(layer "F.SilkS")
		)
		(fp_line
			(start 0.7874 -0.4064)
			(end 0.7874 0.4064)
			(stroke
				(width 0.1524)
				(type default)
			)
			(layer "F.SilkS")
		)
		(fp_line
			(start 0.7874 0.4064)
			(end -0.7874 0.4064)
			(stroke
				(width 0.1524)
				(type default)
			)
			(layer "F.SilkS")
		)
		(fp_poly
			(pts
				(xy -0.508 0.2794) (xy -0.508 0.2286) (xy -0.635 0.2286) (xy -0.635 -0.254) (xy -0.5334 -0.254)
				(xy -0.5334 -0.2794) (xy 0.5334 -0.2794) (xy 0.5334 -0.254) (xy 0.635 -0.254) (xy 0.635 0.254) (xy 0.5334 0.254)
				(xy 0.5334 0.2794)
			)
			(stroke
				(width 0)
				(type default)
			)
			(fill no)
			(layer "F.CrtYd")
		)
		(pad "1" smd rect
			(at 0.40005 0)
			(size 0.4572 0.508)
			(layers "F.Cu" "F.Mask" "F.Paste")
			(net "TMP05_FUNC1")
		)
		(pad "2" smd rect
			(at -0.40005 0)
			(size 0.4572 0.508)
			(layers "F.Cu" "F.Mask" "F.Paste")
			(net "P3V3_NODE1")
		)
	)
	(footprint ""
		(layer "F.Cu")
		(at 27.438604 -123.262644 -90)
		(property "Reference" "R1233"
			(at 4.09702 1.30175 90)
			(unlocked yes)
			(layer "F.SilkS")
			(effects
				(font
					(size 0.7874 0.5842)
					(thickness 0.1524)
				)
				(justify left)
			)
		)
		(property "Value" ""
			(at 0 0 270)
			(layer "F.Fab")
			(effects
				(font
					(size 1.27 1.27)
				)
			)
		)
		(duplicate_pad_numbers_are_jumpers no)
		(fp_line
			(start -0.7874 0.4064)
			(end -0.7874 -0.4064)
			(stroke
				(width 0.1524)
				(type default)
			)
			(layer "F.SilkS")
		)
		(fp_line
			(start 0.7874 0.4064)
			(end -0.7874 0.4064)
			(stroke
				(width 0.1524)
				(type default)
			)
			(layer "F.SilkS")
		)
		(fp_line
			(start -0.7874 -0.4064)
			(end 0.7874 -0.4064)
			(stroke
				(width 0.1524)
				(type default)
			)
			(layer "F.SilkS")
		)
		(fp_line
			(start 0.7874 -0.4064)
			(end 0.7874 0.4064)
			(stroke
				(width 0.1524)
				(type default)
			)
			(layer "F.SilkS")
		)
		(fp_poly
			(pts
				(xy -0.508 0.2794) (xy -0.508 0.2286) (xy -0.635 0.2286) (xy -0.635 -0.254) (xy -0.5334 -0.254)
				(xy -0.5334 -0.2794) (xy 0.5334 -0.2794) (xy 0.5334 -0.254) (xy 0.635 -0.254) (xy 0.635 0.254) (xy 0.5334 0.254)
				(xy 0.5334 0.2794)
			)
			(stroke
				(width 0)
				(type default)
			)
			(fill no)
			(layer "F.CrtYd")
		)
		(pad "1" smd rect
			(at 0.40005 0 270)
			(size 0.4572 0.508)
			(layers "F.Cu" "F.Mask" "F.Paste")
			(net "GND")
		)
		(pad "2" smd rect
			(at -0.40005 0 270)
			(size 0.4572 0.508)
			(layers "F.Cu" "F.Mask" "F.Paste")
			(net "FM_CPLD_NODE1_P1V538_BMC_EN")
		)
	)
	(footprint ""
		(layer "F.Cu")
		(at 72.500998 -10.893044 180)
		(property "Reference" "PC43"
			(at -2.883154 -0.431038 0)
			(unlocked yes)
			(layer "F.SilkS")
			(effects
				(font
					(size 0.7874 0.5842)
					(thickness 0.1524)
				)
				(justify left)
			)
		)
		(property "Value" ""
			(at 0 0 180)
			(layer "F.Fab")
			(effects
				(font
					(size 1.27 1.27)
				)
			)
		)
		(duplicate_pad_numbers_are_jumpers no)
		(fp_line
			(start 2.2098 0.9398)
			(end -2.2098 0.9398)
			(stroke
				(width 0.1524)
				(type default)
			)
			(layer "F.SilkS")
		)
		(fp_line
			(start 2.2098 -0.9398)
			(end 2.2098 0.9398)
			(stroke
				(width 0.1524)
				(type default)
			)
			(layer "F.SilkS")
		)
		(fp_line
			(start 0 -0.9398)
			(end 0 0.9398)
			(stroke
				(width 0.1524)
				(type default)
			)
			(layer "F.SilkS")
		)
		(fp_line
			(start -2.2098 0.9398)
			(end -2.2098 -0.9398)
			(stroke
				(width 0.1524)
				(type default)
			)
			(layer "F.SilkS")
		)
		(fp_line
			(start -2.2098 -0.9398)
			(end 2.2098 -0.9398)
			(stroke
				(width 0.1524)
				(type default)
			)
			(layer "F.SilkS")
		)
		(fp_poly
			(pts
				(xy -1.6764 0.889) (xy -1.6764 0.7874) (xy -2.0574 0.7874) (xy -2.0574 -0.7874) (xy -1.6764 -0.7874)
				(xy -1.6764 -0.9398) (xy 1.6764 -0.9398) (xy 1.6764 -0.7874) (xy 2.0574 -0.7874) (xy 2.0574 0.7874)
				(xy 1.6764 0.7874) (xy 1.6764 0.9398) (xy -1.6764 0.9398)
			)
			(stroke
				(width 0)
				(type default)
			)
			(fill no)
			(layer "F.CrtYd")
		)
		(fp_line
			(start 1.700022 0.899922)
			(end -1.700022 0.899922)
			(stroke
				(width 0.1)
				(type default)
			)
			(layer "F.Fab")
		)
		(fp_line
			(start 1.700022 -0.899922)
			(end 1.700022 0.899922)
			(stroke
				(width 0.1)
				(type default)
			)
			(layer "F.Fab")
		)
		(fp_line
			(start -1.700022 0.899922)
			(end -1.700022 -0.899922)
			(stroke
				(width 0.1)
				(type default)
			)
			(layer "F.Fab")
		)
		(fp_line
			(start -1.700022 -0.899922)
			(end 1.700022 -0.899922)
			(stroke
				(width 0.1)
				(type default)
			)
			(layer "F.Fab")
		)
		(pad "1" smd rect
			(at 1.4732 0 180)
			(size 1.1684 1.5748)
			(layers "F.Cu" "F.Mask" "F.Paste")
			(net "P12V_AUX")
		)
		(pad "2" smd rect
			(at -1.4732 0 180)
			(size 1.1684 1.5748)
			(layers "F.Cu" "F.Mask" "F.Paste")
			(net "GND")
		)
	)
	(footprint ""
		(layer "F.Cu")
		(at 185.817764 -113.548922 90)
		(property "Reference" "R1029"
			(at -3.457448 -0.987806 0)
			(unlocked yes)
			(layer "F.SilkS")
			(effects
				(font
					(size 0.7874 0.5842)
					(thickness 0.1524)
				)
				(justify left)
			)
		)
		(property "Value" ""
			(at 0 0 90)
			(layer "F.Fab")
			(effects
				(font
					(size 1.27 1.27)
				)
			)
		)
		(duplicate_pad_numbers_are_jumpers no)
		(fp_line
			(start 0.7874 -0.4064)
			(end 0.7874 0.4064)
			(stroke
				(width 0.1524)
				(type default)
			)
			(layer "F.SilkS")
		)
		(fp_line
			(start -0.7874 -0.4064)
			(end 0.7874 -0.4064)
			(stroke
				(width 0.1524)
				(type default)
			)
			(layer "F.SilkS")
		)
		(fp_line
			(start 0.7874 0.4064)
			(end -0.7874 0.4064)
			(stroke
				(width 0.1524)
				(type default)
			)
			(layer "F.SilkS")
		)
		(fp_line
			(start -0.7874 0.4064)
			(end -0.7874 -0.4064)
			(stroke
				(width 0.1524)
				(type default)
			)
			(layer "F.SilkS")
		)
		(fp_poly
			(pts
				(xy -0.508 0.2794) (xy -0.508 0.2286) (xy -0.635 0.2286) (xy -0.635 -0.254) (xy -0.5334 -0.254)
				(xy -0.5334 -0.2794) (xy 0.5334 -0.2794) (xy 0.5334 -0.254) (xy 0.635 -0.254) (xy 0.635 0.254) (xy 0.5334 0.254)
				(xy 0.5334 0.2794)
			)
			(stroke
				(width 0)
				(type default)
			)
			(fill no)
			(layer "F.CrtYd")
		)
		(pad "1" smd rect
			(at 0.40005 0 90)
			(size 0.4572 0.508)
			(layers "F.Cu" "F.Mask" "F.Paste")
			(net "PWRGD_NODE1_P12V_PG_R")
		)
		(pad "2" smd rect
			(at -0.40005 0 90)
			(size 0.4572 0.508)
			(layers "F.Cu" "F.Mask" "F.Paste")
			(net "GND")
		)
	)
)
